# BASEBOARD_FAB2 (Tioga Pass) — schematic netlist excerpt (pin names and nets, part order shuffled) for the footprints in the layout excerpt that follows; sources: Cadence DE-HDL packaged netlist, KiCad conversion of Wiwynn_Tioga_Pass_MB.brd

C4M3  CAP  10UF 4V 20% X6S  pkg 0603LF  page 232 : A = PVPP_DEF ; B = GND
C3L19  CAPP  470UF 2V 20% ALUM  pkg SM  page 236 : A = P1V05_PCH_STBY ; B = GND
C8P8  CAP  100UF 4V 20% X5R  pkg 0805  page 76 : A = PVCCMCP_CPU1 ; B = GND

(kicad_pcb
	(version 20260206)
	(generator "pcbnew")
	(generator_version "10.0")
	(general
		(thickness 1.6)
		(legacy_teardrops no)
	)
	(paper "A4")
	(title_block
		(title "Wiwynn_Tioga_Pass_MB.brd")
		(comment 1 "Tioga Pass / footprints 2661-2663 of 4770")
	)
	(layers
		(0 "F.Cu" signal "TOP")
		(4 "In1.Cu" signal "L2GND")
		(6 "In2.Cu" signal "L3")
		(8 "In3.Cu" signal "L4GND")
		(10 "In4.Cu" signal "L5")
		(12 "In5.Cu" signal "L6GND")
		(14 "In6.Cu" signal "L7VCC")
		(16 "In7.Cu" signal "L8VCC")
		(18 "In8.Cu" signal "L9GND")
		(20 "In9.Cu" signal "L10")
		(22 "In10.Cu" signal "L11GND")
		(24 "In11.Cu" signal "L12")
		(26 "In12.Cu" signal "L13GND")
		(2 "B.Cu" signal "BOTTOM")
		(9 "F.Adhes" user "F.Adhesive")
		(11 "B.Adhes" user "B.Adhesive")
		(13 "F.Paste" user "Package Geometry/Pastemask Top")
		(15 "B.Paste" user "Package Geometry/Pastemask Bottom")
		(5 "F.SilkS" user "Ref Des/Silkscreen Top")
		(7 "B.SilkS" user "Ref Des/Silkscreen Bottom")
		(1 "F.Mask" user "Board Geometry/Soldermask Top")
		(3 "B.Mask" user "Board Geometry/Soldermask Bottom")
		(17 "Dwgs.User" user "User.Drawings")
		(19 "Cmts.User" user "User.Comments")
		(21 "Eco1.User" user "User.Eco1")
		(23 "Eco2.User" user "User.Eco2")
		(25 "Edge.Cuts" user "Board Geometry/Outline")
		(27 "Margin" user)
		(31 "F.CrtYd" user "Package Geometry/Place Bound Top")
		(29 "B.CrtYd" user "Package Geometry/Place Bound Bottom")
		(35 "F.Fab" user "Ref Des/Assembly Top")
		(33 "B.Fab" user "Ref Des/Assembly Bottom")
	)
	(footprint ""
		(layer "B.Cu")
		(at 106.731054 -79.60614 180)
		(property "Reference" "C8P8"
			(at 0 0 0)
			(layer "B.SilkS")
			(hide yes)
			(effects
				(font
					(size 1.27 1.27)
				)
				(justify mirror)
			)
		)
		(property "Value" ""
			(at 0 0 0)
			(layer "B.Fab")
			(effects
				(font
					(size 1.27 1.27)
				)
				(justify mirror)
			)
		)
		(duplicate_pad_numbers_are_jumpers no)
		(fp_poly
			(pts
				(xy 0.7239 -0.2159) (xy -0.7239 -0.2159) (xy -0.7239 1.9939) (xy 0.7239 1.9939)
			)
			(stroke
				(width 0)
				(type default)
			)
			(fill no)
			(layer "B.CrtYd")
		)
		(fp_line
			(start 0.7239 1.9939)
			(end -0.7239 1.9939)
			(stroke
				(width 0.1)
				(type default)
			)
			(layer "B.Fab")
		)
		(fp_line
			(start 0.7239 -0.2159)
			(end 0.7239 1.9939)
			(stroke
				(width 0.1)
				(type default)
			)
			(layer "B.Fab")
		)
		(fp_line
			(start -0.7239 1.9939)
			(end -0.7239 -0.2159)
			(stroke
				(width 0.1)
				(type default)
			)
			(layer "B.Fab")
		)
		(fp_line
			(start -0.7239 -0.2159)
			(end 0.7239 -0.2159)
			(stroke
				(width 0.1)
				(type default)
			)
			(layer "B.Fab")
		)
		(pad "1" smd rect
			(at 0 0)
			(size 1.27 1.016)
			(layers "B.Cu" "B.Mask" "B.Paste")
			(net "PVCCMCP_CPU1")
		)
		(pad "2" smd rect
			(at 0 1.778)
			(size 1.27 1.016)
			(layers "B.Cu" "B.Mask" "B.Paste")
			(net "GND")
		)
		(zone
			(layer "B.Cu")
			(hatch none 0.5)
			(connect_pads
				(clearance 0)
			)
			(min_thickness 0.25)
			(keepout
				(tracks not_allowed)
				(vias allowed)
				(pads allowed)
				(copperpour not_allowed)
				(footprints allowed)
			)
			(placement
				(enabled no)
				(sheetname "")
			)
			(fill
				(thermal_gap 0.5)
				(thermal_bridge_width 0.5)
				(island_removal_mode 0)
			)
			(polygon
				(pts
					(xy 106.096054 -80.11414) (xy 107.366054 -80.11414) (xy 107.366054 -80.87614) (xy 106.096054 -80.87614)
				)
			)
		)
	)
	(footprint ""
		(layer "B.Cu")
		(at 385.826 -140.589 180)
		(property "Reference" "C3L19"
			(at -3.10007 3.24612 270)
			(unlocked yes)
			(layer "B.SilkS")
			(effects
				(font
					(size 0.7874 0.5842)
					(thickness 0.1524)
				)
				(justify mirror)
			)
		)
		(property "Value" ""
			(at 0 0 0)
			(layer "B.Fab")
			(effects
				(font
					(size 1.27 1.27)
				)
				(justify mirror)
			)
		)
		(duplicate_pad_numbers_are_jumpers no)
		(fp_line
			(start 2.563114 1.633728)
			(end 1.6002 1.633728)
			(stroke
				(width 0.1524)
				(type default)
			)
			(layer "B.SilkS")
		)
		(fp_line
			(start 2.563114 -1.616456)
			(end 2.563114 1.633728)
			(stroke
				(width 0.1524)
				(type default)
			)
			(layer "B.SilkS")
		)
		(fp_line
			(start 2.286 7.366)
			(end 2.286 1.632712)
			(stroke
				(width 0.1524)
				(type default)
			)
			(layer "B.SilkS")
		)
		(fp_line
			(start 2.286 7.366)
			(end 1.60147 7.366)
			(stroke
				(width 0.1524)
				(type default)
			)
			(layer "B.SilkS")
		)
		(fp_line
			(start 1.6002 -1.616456)
			(end 2.563114 -1.616456)
			(stroke
				(width 0.1524)
				(type default)
			)
			(layer "B.SilkS")
		)
		(fp_line
			(start -1.6002 -1.616456)
			(end -2.504948 -1.616456)
			(stroke
				(width 0.1524)
				(type default)
			)
			(layer "B.SilkS")
		)
		(fp_line
			(start -2.286 7.366)
			(end -1.600708 7.366)
			(stroke
				(width 0.1524)
				(type default)
			)
			(layer "B.SilkS")
		)
		(fp_line
			(start -2.286 7.366)
			(end -2.286 1.63195)
			(stroke
				(width 0.1524)
				(type default)
			)
			(layer "B.SilkS")
		)
		(fp_line
			(start -2.504948 1.633728)
			(end -1.6002 1.633728)
			(stroke
				(width 0.1524)
				(type default)
			)
			(layer "B.SilkS")
		)
		(fp_line
			(start -2.504948 -1.616456)
			(end -2.504948 1.633728)
			(stroke
				(width 0.1524)
				(type default)
			)
			(layer "B.SilkS")
		)
		(fp_rect
			(start 2.286 7.366)
			(end -2.286 -0.254)
			(stroke
				(width 0)
				(type default)
			)
			(fill no)
			(layer "B.CrtYd")
		)
		(fp_line
			(start 2.286 7.366)
			(end 2.286 -0.254)
			(stroke
				(width 0.1)
				(type default)
			)
			(layer "B.Fab")
		)
		(fp_line
			(start 2.286 -0.254)
			(end -2.286 -0.254)
			(stroke
				(width 0.1)
				(type default)
			)
			(layer "B.Fab")
		)
		(fp_line
			(start -2.286 7.366)
			(end 2.286 7.366)
			(stroke
				(width 0.1)
				(type default)
			)
			(layer "B.Fab")
		)
		(fp_line
			(start -2.286 -0.254)
			(end -2.286 7.366)
			(stroke
				(width 0.1)
				(type default)
			)
			(layer "B.Fab")
		)
		(pad "1" smd rect
			(at 0 0)
			(size 2.54 3.048)
			(layers "B.Cu" "B.Mask" "B.Paste")
			(net "P1V05_PCH_STBY")
		)
		(pad "2" smd rect
			(at 0 7.112)
			(size 2.54 3.048)
			(layers "B.Cu" "B.Mask" "B.Paste")
			(net "GND")
		)
	)
	(footprint ""
		(layer "B.Cu")
		(at 320.194432 -135.382 90)
		(property "Reference" "C4M3"
			(at 0 0 90)
			(layer "B.SilkS")
			(hide yes)
			(effects
				(font
					(size 1.27 1.27)
				)
				(justify mirror)
			)
		)
		(property "Value" ""
			(at 0 0 90)
			(layer "B.Fab")
			(effects
				(font
					(size 1.27 1.27)
				)
				(justify mirror)
			)
		)
		(duplicate_pad_numbers_are_jumpers no)
		(fp_poly
			(pts
				(xy 0.4953 -0.2032) (xy -0.4953 -0.2032) (xy -0.4953 1.6002) (xy 0.4953 1.6002)
			)
			(stroke
				(width 0)
				(type default)
			)
			(fill no)
			(layer "B.CrtYd")
		)
		(fp_line
			(start 0.4953 -0.2032)
			(end -0.4953 -0.2032)
			(stroke
				(width 0.1)
				(type default)
			)
			(layer "B.Fab")
		)
		(fp_line
			(start -0.4953 -0.2032)
			(end -0.4953 1.6002)
			(stroke
				(width 0.1)
				(type default)
			)
			(layer "B.Fab")
		)
		(fp_line
			(start 0.4953 1.6002)
			(end 0.4953 -0.2032)
			(stroke
				(width 0.1)
				(type default)
			)
			(layer "B.Fab")
		)
		(fp_line
			(start -0.4953 1.6002)
			(end 0.4953 1.6002)
			(stroke
				(width 0.1)
				(type default)
			)
			(layer "B.Fab")
		)
		(pad "1" smd rect
			(at 0 0 270)
			(size 0.762 0.889)
			(layers "B.Cu" "B.Mask" "B.Paste")
			(net "PVPP_DEF")
		)
		(pad "2" smd rect
			(at 0 1.397 270)
			(size 0.762 0.889)
			(layers "B.Cu" "B.Mask" "B.Paste")
			(net "GND")
		)
		(zone
			(layer "B.Cu")
			(hatch none 0.5)
			(connect_pads
				(clearance 0)
			)
			(min_thickness 0.25)
			(keepout
				(tracks not_allowed)
				(vias allowed)
				(pads allowed)
				(copperpour not_allowed)
				(footprints allowed)
			)
			(placement
				(enabled no)
				(sheetname "")
			)
			(fill
				(thermal_gap 0.5)
				(thermal_bridge_width 0.5)
				(island_removal_mode 0)
			)
			(polygon
				(pts
					(xy 320.638932 -135.763) (xy 320.638932 -135.001) (xy 321.146932 -135.001) (xy 321.146932 -135.763)
				)
			)
		)
	)
)
